(kicad_pcb
	(version 20241229)
	(generator "pcbnew")
	(generator_version "9.0")
	(general
		(thickness 1.62)
		(legacy_teardrops no)
	)
	(paper "A3")
	(title_block
		(title "COM Express 7 Baseboard")
		(date "2025-02-04")
		(rev "1.1.2")
		(company "Antmicro Ltd")
		(comment 1 "www.antmicro.com")
		(comment 9 "footprints 143-145 of 802")
	)
	(layers
		(0 "F.Cu" signal)
		(4 "In1.Cu" signal)
		(6 "In2.Cu" signal)
		(8 "In3.Cu" signal)
		(10 "In4.Cu" signal)
		(12 "In5.Cu" signal)
		(14 "In6.Cu" signal)
		(2 "B.Cu" signal)
		(9 "F.Adhes" user "F.Adhesive")
		(11 "B.Adhes" user "B.Adhesive")
		(13 "F.Paste" user)
		(15 "B.Paste" user)
		(5 "F.SilkS" user "F.Silkscreen")
		(7 "B.SilkS" user "B.Silkscreen")
		(1 "F.Mask" user)
		(3 "B.Mask" user)
		(17 "Dwgs.User" user "User.Drawings")
		(19 "Cmts.User" user "User.Comments")
		(21 "Eco1.User" user "User.Eco1")
		(23 "Eco2.User" user "User.Eco2")
		(25 "Edge.Cuts" user)
		(27 "Margin" user)
		(31 "F.CrtYd" user "F.Courtyard")
		(29 "B.CrtYd" user "B.Courtyard")
		(35 "F.Fab" user)
		(33 "B.Fab" user)
	)
	(footprint "antmicro-footprints:SOT-23-3"
		(layer "F.Cu")
		(at 317.1 112.66)
		(property "Reference" "Q10"
			(at 1.85 -0.6 90)
			(layer "F.SilkS")
			(effects
				(font
					(size 0.7 0.7)
					(thickness 0.15)
				)
				(justify left bottom)
			)
		)
		(property "Value" "MMBT3904LT1G"
			(at -1.9 2.7 0)
			(layer "F.Fab")
			(effects
				(font
					(size 0.7 0.7)
					(thickness 0.15)
				)
				(justify left bottom)
			)
		)
		(property "Datasheet" "https://eu.mouser.com/datasheet/2/308/1/MMBT3904LT1_D-2316262.pdf"
			(at 0 0 0)
			(layer "F.Fab")
			(hide yes)
			(effects
				(font
					(size 1.27 1.27)
					(thickness 0.15)
				)
			)
		)
		(property "Author" "Antmicro"
			(at 0 0 0)
			(layer "F.Fab")
			(hide yes)
			(effects
				(font
					(size 1 1)
					(thickness 0.15)
				)
			)
		)
		(property "License" "Apache-2.0"
			(at 0 0 0)
			(layer "F.Fab")
			(hide yes)
			(effects
				(font
					(size 1 1)
					(thickness 0.15)
				)
			)
		)
		(property "MPN" "MMBT3904LT1G"
			(at 0 0 0)
			(layer "F.Fab")
			(hide yes)
			(effects
				(font
					(size 1 1)
					(thickness 0.15)
				)
			)
		)
		(property "Manufacturer" "Onsemi"
			(at 0 0 0)
			(layer "F.Fab")
			(hide yes)
			(effects
				(font
					(size 1 1)
					(thickness 0.15)
				)
			)
		)
		(property "Public" "False"
			(at 0 0 0)
			(layer "F.Fab")
			(hide yes)
			(effects
				(font
					(size 1 1)
					(thickness 0.15)
				)
			)
		)
		(property ki_fp_filters "SOT?323*")
		(sheetname "Misc")
		(sheetfile "misc.kicad_sch")
		(attr smd)
		(fp_line
			(start -1.45 -1.35)
			(end -0.85 -1.35)
			(stroke
				(width 0.15)
				(type solid)
			)
			(layer "F.SilkS")
		)
		(fp_line
			(start -0.85 -1.35)
			(end -0.7 -1.5)
			(stroke
				(width 0.15)
				(type solid)
			)
			(layer "F.SilkS")
		)
		(fp_line
			(start -0.7 1.5)
			(end -0.7 1.35)
			(stroke
				(width 0.15)
				(type solid)
			)
			(layer "F.SilkS")
		)
		(fp_line
			(start 0.7 -1.5)
			(end -0.7 -1.5)
			(stroke
				(width 0.15)
				(type solid)
			)
			(layer "F.SilkS")
		)
		(fp_line
			(start 0.7 -0.4)
			(end 0.7 -1.5)
			(stroke
				(width 0.15)
				(type solid)
			)
			(layer "F.SilkS")
		)
		(fp_line
			(start 0.7 0.4)
			(end 0.7 1.5)
			(stroke
				(width 0.15)
				(type solid)
			)
			(layer "F.SilkS")
		)
		(fp_line
			(start 0.7 1.5)
			(end -0.7 1.5)
			(stroke
				(width 0.15)
				(type solid)
			)
			(layer "F.SilkS")
		)
		(fp_line
			(start -1.75 -0.5)
			(end -1.75 -1.4)
			(stroke
				(width 0.05)
				(type solid)
			)
			(layer "F.CrtYd")
		)
		(fp_line
			(start -1.75 0.5)
			(end -0.85 0.5)
			(stroke
				(width 0.05)
				(type solid)
			)
			(layer "F.CrtYd")
		)
		(fp_line
			(start -1.75 1.4)
			(end -1.75 0.5)
			(stroke
				(width 0.05)
				(type solid)
			)
			(layer "F.CrtYd")
		)
		(fp_line
			(start -0.9 -1.6)
			(end -0.9 -1.4)
			(stroke
				(width 0.05)
				(type solid)
			)
			(layer "F.CrtYd")
		)
		(fp_line
			(start -0.9 -1.6)
			(end 0.825 -1.6)
			(stroke
				(width 0.05)
				(type solid)
			)
			(layer "F.CrtYd")
		)
		(fp_line
			(start -0.9 -1.4)
			(end -1.75 -1.4)
			(stroke
				(width 0.05)
				(type solid)
			)
			(layer "F.CrtYd")
		)
		(fp_line
			(start -0.85 -0.5)
			(end -1.75 -0.5)
			(stroke
				(width 0.05)
				(type solid)
			)
			(layer "F.CrtYd")
		)
		(fp_line
			(start -0.85 0.5)
			(end -0.85 -0.5)
			(stroke
				(width 0.05)
				(type solid)
			)
			(layer "F.CrtYd")
		)
		(fp_line
			(start -0.85 1.4)
			(end -1.75 1.4)
			(stroke
				(width 0.05)
				(type solid)
			)
			(layer "F.CrtYd")
		)
		(fp_line
			(start -0.85 1.65)
			(end -0.85 1.4)
			(stroke
				(width 0.05)
				(type solid)
			)
			(layer "F.CrtYd")
		)
		(fp_line
			(start 0.825 -1.6)
			(end 0.825 -0.45)
			(stroke
				(width 0.05)
				(type solid)
			)
			(layer "F.CrtYd")
		)
		(fp_line
			(start 0.825 -0.45)
			(end 1.75 -0.45)
			(stroke
				(width 0.05)
				(type solid)
			)
			(layer "F.CrtYd")
		)
		(fp_line
			(start 0.85 0.45)
			(end 0.85 1.65)
			(stroke
				(width 0.05)
				(type solid)
			)
			(layer "F.CrtYd")
		)
		(fp_line
			(start 0.85 1.65)
			(end -0.85 1.65)
			(stroke
				(width 0.05)
				(type solid)
			)
			(layer "F.CrtYd")
		)
		(fp_line
			(start 1.75 -0.45)
			(end 1.75 0.45)
			(stroke
				(width 0.05)
				(type solid)
			)
			(layer "F.CrtYd")
		)
		(fp_line
			(start 1.75 0.45)
			(end 0.85 0.45)
			(stroke
				(width 0.05)
				(type solid)
			)
			(layer "F.CrtYd")
		)
		(fp_line
			(start -0.712 -1.325)
			(end -0.712 1.523)
			(stroke
				(width 0.15)
				(type solid)
			)
			(layer "F.Fab")
		)
		(fp_line
			(start -0.712 1.519)
			(end 0.688 1.519)
			(stroke
				(width 0.15)
				(type solid)
			)
			(layer "F.Fab")
		)
		(fp_line
			(start -0.437 -1.526)
			(end -0.712 -1.325)
			(stroke
				(width 0.15)
				(type solid)
			)
			(layer "F.Fab")
		)
		(fp_line
			(start -0.437 -1.526)
			(end 0.688 -1.526)
			(stroke
				(width 0.15)
				(type solid)
			)
			(layer "F.Fab")
		)
		(fp_line
			(start 0.688 1.519)
			(end 0.688 -1.52)
			(stroke
				(width 0.15)
				(type solid)
			)
			(layer "F.Fab")
		)
		(pad "1" smd roundrect
			(at -1.1 -0.951)
			(size 1 0.6)
			(layers "F.Cu" "F.Mask" "F.Paste")
			(roundrect_rratio 0.15)
			(net 543 "Net-(Q10-B)")
			(pinfunction "B")
			(pintype "input")
			(teardrops
				(best_length_ratio 0.2)
				(max_length 1)
				(best_width_ratio 0.9)
				(max_width 2)
				(curved_edges yes)
				(filter_ratio 0.9)
				(enabled yes)
				(allow_two_segments yes)
				(prefer_zone_connections yes)
			)
		)
		(pad "2" smd roundrect
			(at -1.1 0.949)
			(size 1 0.6)
			(layers "F.Cu" "F.Mask" "F.Paste")
			(roundrect_rratio 0.15)
			(net 544 "Net-(Q10-E)")
			(pinfunction "E")
			(pintype "passive")
			(teardrops
				(best_length_ratio 0.2)
				(max_length 1)
				(best_width_ratio 0.9)
				(max_width 2)
				(curved_edges yes)
				(filter_ratio 0.9)
				(enabled yes)
				(allow_two_segments yes)
				(prefer_zone_connections yes)
			)
		)
		(pad "3" smd roundrect
			(at 1.1 -0.0005)
			(size 1 0.6)
			(layers "F.Cu" "F.Mask" "F.Paste")
			(roundrect_rratio 0.15)
			(net 543 "Net-(Q10-B)")
			(pinfunction "C")
			(pintype "passive")
			(teardrops
				(best_length_ratio 0.2)
				(max_length 1)
				(best_width_ratio 0.9)
				(max_width 2)
				(curved_edges yes)
				(filter_ratio 0.9)
				(enabled yes)
				(allow_two_segments yes)
				(prefer_zone_connections yes)
			)
		)
	)
	(footprint "antmicro-footprints:R_0201"
		(layer "F.Cu")
		(at 150.33 147.961 -90)
		(descr "Resistor SMD 0201")
		(tags "resistor SMD 0201")
		(property "Reference" "R276"
			(at 3.62 -0.57 90)
			(layer "F.SilkS")
			(effects
				(font
					(size 0.7 0.7)
					(thickness 0.15)
				)
				(justify right bottom)
			)
		)
		(property "Value" "R_0R_0201"
			(at 0 1.25 90)
			(layer "F.Fab")
			(effects
				(font
					(size 0.7 0.7)
					(thickness 0.15)
				)
				(justify right bottom)
			)
		)
		(property "Datasheet" "https://www.bourns.com/docs/product-datasheets/cr.pdf"
			(at 0 0 270)
			(layer "F.Fab")
			(hide yes)
			(effects
				(font
					(size 1.27 1.27)
					(thickness 0.15)
				)
			)
		)
		(property "Author" "Antmicro"
			(at 2.369 298.291 0)
			(layer "F.Fab")
			(hide yes)
			(effects
				(font
					(size 1 1)
					(thickness 0.15)
				)
			)
		)
		(property "License" "Apache-2.0"
			(at 2.369 298.291 0)
			(layer "F.Fab")
			(hide yes)
			(effects
				(font
					(size 1 1)
					(thickness 0.15)
				)
			)
		)
		(property "MPN" "CR0201-FX-0R00GLF"
			(at 2.369 298.291 0)
			(layer "F.Fab")
			(hide yes)
			(effects
				(font
					(size 1 1)
					(thickness 0.15)
				)
			)
		)
		(property "Manufacturer" "Bourns"
			(at 2.369 298.291 0)
			(layer "F.Fab")
			(hide yes)
			(effects
				(font
					(size 1 1)
					(thickness 0.15)
				)
			)
		)
		(property "Tolerance" "1%"
			(at 2.369 298.291 0)
			(layer "F.Fab")
			(hide yes)
			(effects
				(font
					(size 1 1)
					(thickness 0.15)
				)
			)
		)
		(property "Val" "0R"
			(at 2.369 298.291 0)
			(layer "F.Fab")
			(hide yes)
			(effects
				(font
					(size 1 1)
					(thickness 0.15)
				)
			)
		)
		(sheetname "KR to SFI #1")
		(sheetfile "kr_sfi.kicad_sch")
		(attr smd dnp)
		(fp_rect
			(start -0.7 -0.35)
			(end 0.7 0.35)
			(stroke
				(width 0.05)
				(type default)
			)
			(fill no)
			(layer "F.CrtYd")
		)
		(fp_rect
			(start -0.3 -0.15)
			(end 0.298 0.148)
			(stroke
				(width 0.15)
				(type solid)
			)
			(fill no)
			(layer "F.Fab")
		)
		(pad "" smd roundrect
			(at -0.346 0 270)
			(size 0.318 0.36)
			(layers "F.Paste")
			(roundrect_rratio 0.25)
			(teardrops
				(best_length_ratio 0.2)
				(max_length 1)
				(best_width_ratio 0.9)
				(max_width 2)
				(curved_edges yes)
				(filter_ratio 0.9)
				(enabled yes)
				(allow_two_segments yes)
				(prefer_zone_connections yes)
			)
		)
		(pad "" smd roundrect
			(at 0.344 0 270)
			(size 0.318 0.36)
			(layers "F.Paste")
			(roundrect_rratio 0.25)
			(teardrops
				(best_length_ratio 0.2)
				(max_length 1)
				(best_width_ratio 0.9)
				(max_width 2)
				(curved_edges yes)
				(filter_ratio 0.9)
				(enabled yes)
				(allow_two_segments yes)
				(prefer_zone_connections yes)
			)
		)
		(pad "1" smd roundrect
			(at -0.32 0 270)
			(size 0.46 0.4)
			(layers "F.Cu" "F.Mask")
			(roundrect_rratio 0.25)
			(net 170 "/2xSFP+/SFI0.RX-")
			(pintype "passive")
			(teardrops
				(best_length_ratio 0.2)
				(max_length 1)
				(best_width_ratio 0.9)
				(max_width 2)
				(curved_edges yes)
				(filter_ratio 0.9)
				(enabled yes)
				(allow_two_segments yes)
				(prefer_zone_connections yes)
			)
		)
		(pad "2" smd roundrect
			(at 0.32 0 270)
			(size 0.46 0.4)
			(layers "F.Cu" "F.Mask")
			(roundrect_rratio 0.25)
			(net 967 "/2xSFP+/KR to SFI #1/BYP_RX-")
			(pintype "passive")
			(teardrops
				(best_length_ratio 0.2)
				(max_length 1)
				(best_width_ratio 0.9)
				(max_width 2)
				(curved_edges yes)
				(filter_ratio 0.9)
				(enabled yes)
				(allow_two_segments yes)
				(prefer_zone_connections yes)
			)
		)
	)
	(footprint "antmicro-footprints:C_0201"
		(layer "F.Cu")
		(at 156.332 147.31 90)
		(descr "Capacitor SMD 0201")
		(tags "capacitor SMD 0201")
		(property "Reference" "C154"
			(at -4.125 0.618 90)
			(layer "F.SilkS")
			(effects
				(font
					(size 0.7 0.7)
					(thickness 0.15)
				)
				(justify left bottom)
			)
		)
		(property "Value" "C_100n_0201_25V"
			(at 0 1.4 90)
			(layer "F.Fab")
			(effects
				(font
					(size 0.7 0.7)
					(thickness 0.15)
				)
				(justify left bottom)
			)
		)
		(property "Datasheet" "https://product.tdk.com/en/search/capacitor/ceramic/mlcc/info?part_no=C0603X5R1E104K030BB"
			(at 0 0 90)
			(layer "F.Fab")
			(hide yes)
			(effects
				(font
					(size 1.27 1.27)
					(thickness 0.15)
				)
			)
		)
		(property "Author" "Antmicro"
			(at 303.642 -9.022 0)
			(layer "F.Fab")
			(hide yes)
			(effects
				(font
					(size 1 1)
					(thickness 0.15)
				)
			)
		)
		(property "Dielectric" ""
			(at 303.642 -9.022 0)
			(layer "F.Fab")
			(hide yes)
			(effects
				(font
					(size 1 1)
					(thickness 0.15)
				)
			)
		)
		(property "License" "Apache-2.0"
			(at 303.642 -9.022 0)
			(layer "F.Fab")
			(hide yes)
			(effects
				(font
					(size 1 1)
					(thickness 0.15)
				)
			)
		)
		(property "MPN" "C0603X5R1E104K030BB"
			(at 303.642 -9.022 0)
			(layer "F.Fab")
			(hide yes)
			(effects
				(font
					(size 1 1)
					(thickness 0.15)
				)
			)
		)
		(property "Manufacturer" "TDK"
			(at 303.642 -9.022 0)
			(layer "F.Fab")
			(hide yes)
			(effects
				(font
					(size 1 1)
					(thickness 0.15)
				)
			)
		)
		(property "Public" "False"
			(at 303.642 -9.022 0)
			(layer "F.Fab")
			(hide yes)
			(effects
				(font
					(size 1 1)
					(thickness 0.15)
				)
			)
		)
		(property "Val" "100n"
			(at 303.642 -9.022 0)
			(layer "F.Fab")
			(hide yes)
			(effects
				(font
					(size 1 1)
					(thickness 0.15)
				)
			)
		)
		(property "Voltage" "25V"
			(at 303.642 -9.022 0)
			(layer "F.Fab")
			(hide yes)
			(effects
				(font
					(size 1 1)
					(thickness 0.15)
				)
			)
		)
		(sheetname "KR to SFI #1")
		(sheetfile "kr_sfi.kicad_sch")
		(attr smd)
		(fp_rect
			(start -0.7 -0.35)
			(end 0.7 0.35)
			(stroke
				(width 0.05)
				(type default)
			)
			(fill no)
			(layer "F.CrtYd")
		)
		(fp_rect
			(start 0.3 0.15)
			(end -0.301 -0.149)
			(stroke
				(width 0.15)
				(type solid)
			)
			(fill no)
			(layer "F.Fab")
		)
		(pad "" smd roundrect
			(at -0.349 -0.002 90)
			(size 0.318 0.36)
			(layers "F.Paste")
			(roundrect_rratio 0.25)
			(teardrops
				(best_length_ratio 0.2)
				(max_length 1)
				(best_width_ratio 0.9)
				(max_width 2)
				(curved_edges yes)
				(filter_ratio 0.9)
				(enabled yes)
				(allow_two_segments yes)
				(prefer_zone_connections yes)
			)
		)
		(pad "" smd roundrect
			(at 0.341 -0.002 90)
			(size 0.318 0.36)
			(layers "F.Paste")
			(roundrect_rratio 0.25)
			(teardrops
				(best_length_ratio 0.2)
				(max_length 1)
				(best_width_ratio 0.9)
				(max_width 2)
				(curved_edges yes)
				(filter_ratio 0.9)
				(enabled yes)
				(allow_two_segments yes)
				(prefer_zone_connections yes)
			)
		)
		(pad "1" smd roundrect
			(at -0.321 -0.002 90)
			(size 0.46 0.4)
			(layers "F.Cu" "F.Mask")
			(roundrect_rratio 0.25)
			(net 113 "/2xSFP+/10GKR_SFP0.TX-")
			(pintype "passive")
			(teardrops
				(best_length_ratio 0.2)
				(max_length 1)
				(best_width_ratio 0.9)
				(max_width 2)
				(curved_edges yes)
				(filter_ratio 0.9)
				(enabled yes)
				(allow_two_segments yes)
				(prefer_zone_connections yes)
			)
		)
		(pad "2" smd roundrect
			(at 0.32 -0.002 90)
			(size 0.46 0.4)
			(layers "F.Cu" "F.Mask")
			(roundrect_rratio 0.25)
			(net 114 "/2xSFP+/KR to SFI #1/KR_C.TX-")
			(pintype "passive")
			(teardrops
				(best_length_ratio 0.2)
				(max_length 1)
				(best_width_ratio 0.9)
				(max_width 2)
				(curved_edges yes)
				(filter_ratio 0.9)
				(enabled yes)
				(allow_two_segments yes)
				(prefer_zone_connections yes)
			)
		)
	)
)
